(kicad_pcb
	(version 20260206)
	(generator "pcbnew")
	(generator_version "10.0")
	(general
		(thickness 1.6)
		(legacy_teardrops no)
	)
	(paper "A4")
	(title_block
		(title "Wiwynn_Tioga_Pass_MB.brd")
		(comment 1 "Tioga Pass / footprints 4573-4579 of 4770")
	)
	(layers
		(0 "F.Cu" signal "TOP")
		(4 "In1.Cu" signal "L2GND")
		(6 "In2.Cu" signal "L3")
		(8 "In3.Cu" signal "L4GND")
		(10 "In4.Cu" signal "L5")
		(12 "In5.Cu" signal "L6GND")
		(14 "In6.Cu" signal "L7VCC")
		(16 "In7.Cu" signal "L8VCC")
		(18 "In8.Cu" signal "L9GND")
		(20 "In9.Cu" signal "L10")
		(22 "In10.Cu" signal "L11GND")
		(24 "In11.Cu" signal "L12")
		(26 "In12.Cu" signal "L13GND")
		(2 "B.Cu" signal "BOTTOM")
		(9 "F.Adhes" user "F.Adhesive")
		(11 "B.Adhes" user "B.Adhesive")
		(13 "F.Paste" user "Package Geometry/Pastemask Top")
		(15 "B.Paste" user "Package Geometry/Pastemask Bottom")
		(5 "F.SilkS" user "Ref Des/Silkscreen Top")
		(7 "B.SilkS" user "Ref Des/Silkscreen Bottom")
		(1 "F.Mask" user "Board Geometry/Soldermask Top")
		(3 "B.Mask" user "Board Geometry/Soldermask Bottom")
		(17 "Dwgs.User" user "User.Drawings")
		(19 "Cmts.User" user "User.Comments")
		(21 "Eco1.User" user "User.Eco1")
		(23 "Eco2.User" user "User.Eco2")
		(25 "Edge.Cuts" user "Board Geometry/Outline")
		(27 "Margin" user)
		(31 "F.CrtYd" user "Package Geometry/Place Bound Top")
		(29 "B.CrtYd" user "Package Geometry/Place Bound Bottom")
		(35 "F.Fab" user "Ref Des/Assembly Top")
		(33 "B.Fab" user "Ref Des/Assembly Bottom")
	)
	(footprint ""
		(layer "B.Cu")
		(at 87.158068 -135.4074 -90)
		(property "Reference" "C8M4"
			(at -1.848866 0.752348 270)
			(unlocked yes)
			(layer "B.SilkS")
			(effects
				(font
					(size 1.27 0.9652)
					(thickness 0.1524)
				)
				(justify mirror)
			)
		)
		(property "Value" ""
			(at 0 0 90)
			(layer "B.Fab")
			(effects
				(font
					(size 1.27 1.27)
				)
				(justify mirror)
			)
		)
		(duplicate_pad_numbers_are_jumpers no)
		(fp_rect
			(start 0.500126 1.598422)
			(end -0.500126 -0.201422)
			(stroke
				(width 0)
				(type default)
			)
			(fill no)
			(layer "B.CrtYd")
		)
		(fp_line
			(start -0.500126 1.598422)
			(end 0.500126 1.598422)
			(stroke
				(width 0.1)
				(type default)
			)
			(layer "B.Fab")
		)
		(fp_line
			(start 0.500126 1.598422)
			(end 0.500126 -0.201422)
			(stroke
				(width 0.1)
				(type default)
			)
			(layer "B.Fab")
		)
		(fp_line
			(start -0.500126 -0.201422)
			(end -0.500126 1.598422)
			(stroke
				(width 0.1)
				(type default)
			)
			(layer "B.Fab")
		)
		(fp_line
			(start 0.500126 -0.201422)
			(end -0.500126 -0.201422)
			(stroke
				(width 0.1)
				(type default)
			)
			(layer "B.Fab")
		)
		(pad "1" smd rect
			(at 0 0 180)
			(size 0.889 0.9906)
			(layers "B.Cu" "B.Mask" "B.Paste")
			(net "PVDDQ_KLM")
		)
		(pad "2" smd rect
			(at 0 1.397 180)
			(size 0.889 0.9906)
			(layers "B.Cu" "B.Mask" "B.Paste")
			(net "GND")
		)
		(zone
			(layer "B.Cu")
			(hatch none 0.5)
			(connect_pads
				(clearance 0)
			)
			(min_thickness 0.25)
			(keepout
				(tracks allowed)
				(vias not_allowed)
				(pads allowed)
				(copperpour not_allowed)
				(footprints allowed)
			)
			(placement
				(enabled no)
				(sheetname "")
			)
			(fill
				(thermal_gap 0.5)
				(thermal_bridge_width 0.5)
				(island_removal_mode 0)
			)
			(polygon
				(pts
					(xy 86.205568 -134.9121) (xy 86.713568 -134.9121) (xy 86.713568 -135.9027) (xy 86.205568 -135.9027)
				)
			)
		)
		(zone
			(layer "B.Cu")
			(hatch none 0.5)
			(connect_pads
				(clearance 0)
			)
			(min_thickness 0.25)
			(keepout
				(tracks not_allowed)
				(vias allowed)
				(pads allowed)
				(copperpour not_allowed)
				(footprints allowed)
			)
			(placement
				(enabled no)
				(sheetname "")
			)
			(fill
				(thermal_gap 0.5)
				(thermal_bridge_width 0.5)
				(island_removal_mode 0)
			)
			(polygon
				(pts
					(xy 86.205568 -134.9121) (xy 86.713568 -134.9121) (xy 86.713568 -135.9027) (xy 86.205568 -135.9027)
				)
			)
		)
	)
	(footprint ""
		(layer "B.Cu")
		(at 18.288 -87.7062)
		(property "Reference" "R9P1"
			(at 0 0 0)
			(layer "B.SilkS")
			(hide yes)
			(effects
				(font
					(size 1.27 1.27)
				)
				(justify mirror)
			)
		)
		(property "Value" ""
			(at 0 0 0)
			(layer "B.Fab")
			(effects
				(font
					(size 1.27 1.27)
				)
				(justify mirror)
			)
		)
		(duplicate_pad_numbers_are_jumpers no)
		(fp_poly
			(pts
				(xy 0.2794 -0.1016) (xy -0.2794 -0.1016) (xy -0.2794 0.9906) (xy 0.2794 0.9906)
			)
			(stroke
				(width 0)
				(type default)
			)
			(fill no)
			(layer "B.CrtYd")
		)
		(fp_line
			(start -0.2794 -0.1016)
			(end 0.2794 -0.1016)
			(stroke
				(width 0.1)
				(type default)
			)
			(layer "B.Fab")
		)
		(fp_line
			(start -0.2794 0.9906)
			(end -0.2794 -0.1016)
			(stroke
				(width 0.1)
				(type default)
			)
			(layer "B.Fab")
		)
		(fp_line
			(start 0.2794 -0.1016)
			(end 0.2794 0.9906)
			(stroke
				(width 0.1)
				(type default)
			)
			(layer "B.Fab")
		)
		(fp_line
			(start 0.2794 0.9906)
			(end -0.2794 0.9906)
			(stroke
				(width 0.1)
				(type default)
			)
			(layer "B.Fab")
		)
		(pad "1" smd rect
			(at 0 0 180)
			(size 0.508 0.508)
			(layers "B.Cu" "B.Mask" "B.Paste")
			(net "PVCCIO_CPU1")
		)
		(pad "2" smd rect
			(at 0 0.889 180)
			(size 0.508 0.508)
			(layers "B.Cu" "B.Mask" "B.Paste")
			(net "SVID_DIO0_CPU1_R")
		)
		(zone
			(layer "B.Cu")
			(hatch none 0.5)
			(connect_pads
				(clearance 0)
			)
			(min_thickness 0.25)
			(keepout
				(tracks allowed)
				(vias not_allowed)
				(pads allowed)
				(copperpour not_allowed)
				(footprints allowed)
			)
			(placement
				(enabled no)
				(sheetname "")
			)
			(fill
				(thermal_gap 0.5)
				(thermal_bridge_width 0.5)
				(island_removal_mode 0)
			)
			(polygon
				(pts
					(xy 18.542 -87.4522) (xy 18.034 -87.4522) (xy 18.034 -87.0712) (xy 18.542 -87.0712)
				)
			)
		)
		(zone
			(layer "B.Cu")
			(hatch none 0.5)
			(connect_pads
				(clearance 0)
			)
			(min_thickness 0.25)
			(keepout
				(tracks not_allowed)
				(vias allowed)
				(pads allowed)
				(copperpour not_allowed)
				(footprints allowed)
			)
			(placement
				(enabled no)
				(sheetname "")
			)
			(fill
				(thermal_gap 0.5)
				(thermal_bridge_width 0.5)
				(island_removal_mode 0)
			)
			(polygon
				(pts
					(xy 18.542 -87.0712) (xy 18.034 -87.0712) (xy 18.034 -87.4522) (xy 18.542 -87.4522)
				)
			)
		)
	)
	(footprint ""
		(layer "B.Cu")
		(at 269.559532 -8.1534 90)
		(property "Reference" "C5U4"
			(at -1.848866 0.752348 90)
			(unlocked yes)
			(layer "B.SilkS")
			(effects
				(font
					(size 1.27 0.9652)
					(thickness 0.1524)
				)
				(justify mirror)
			)
		)
		(property "Value" ""
			(at 0 0 90)
			(layer "B.Fab")
			(effects
				(font
					(size 1.27 1.27)
				)
				(justify mirror)
			)
		)
		(duplicate_pad_numbers_are_jumpers no)
		(fp_rect
			(start 0.500126 1.598422)
			(end -0.500126 -0.201422)
			(stroke
				(width 0)
				(type default)
			)
			(fill no)
			(layer "B.CrtYd")
		)
		(fp_line
			(start 0.500126 -0.201422)
			(end -0.500126 -0.201422)
			(stroke
				(width 0.1)
				(type default)
			)
			(layer "B.Fab")
		)
		(fp_line
			(start -0.500126 -0.201422)
			(end -0.500126 1.598422)
			(stroke
				(width 0.1)
				(type default)
			)
			(layer "B.Fab")
		)
		(fp_line
			(start 0.500126 1.598422)
			(end 0.500126 -0.201422)
			(stroke
				(width 0.1)
				(type default)
			)
			(layer "B.Fab")
		)
		(fp_line
			(start -0.500126 1.598422)
			(end 0.500126 1.598422)
			(stroke
				(width 0.1)
				(type default)
			)
			(layer "B.Fab")
		)
		(pad "1" smd rect
			(at 0 0)
			(size 0.889 0.9906)
			(layers "B.Cu" "B.Mask" "B.Paste")
			(net "PVDDQ_ABC")
		)
		(pad "2" smd rect
			(at 0 1.397)
			(size 0.889 0.9906)
			(layers "B.Cu" "B.Mask" "B.Paste")
			(net "GND")
		)
		(zone
			(layer "B.Cu")
			(hatch none 0.5)
			(connect_pads
				(clearance 0)
			)
			(min_thickness 0.25)
			(keepout
				(tracks allowed)
				(vias not_allowed)
				(pads allowed)
				(copperpour not_allowed)
				(footprints allowed)
			)
			(placement
				(enabled no)
				(sheetname "")
			)
			(fill
				(thermal_gap 0.5)
				(thermal_bridge_width 0.5)
				(island_removal_mode 0)
			)
			(polygon
				(pts
					(xy 270.512032 -8.6487) (xy 270.004032 -8.6487) (xy 270.004032 -7.6581) (xy 270.512032 -7.6581)
				)
			)
		)
		(zone
			(layer "B.Cu")
			(hatch none 0.5)
			(connect_pads
				(clearance 0)
			)
			(min_thickness 0.25)
			(keepout
				(tracks not_allowed)
				(vias allowed)
				(pads allowed)
				(copperpour not_allowed)
				(footprints allowed)
			)
			(placement
				(enabled no)
				(sheetname "")
			)
			(fill
				(thermal_gap 0.5)
				(thermal_bridge_width 0.5)
				(island_removal_mode 0)
			)
			(polygon
				(pts
					(xy 270.512032 -8.6487) (xy 270.004032 -8.6487) (xy 270.004032 -7.6581) (xy 270.512032 -7.6581)
				)
			)
		)
	)
	(footprint ""
		(layer "B.Cu")
		(at 236.715808 -164.90188 -90)
		(property "Reference" "T1D15"
			(at 0 0 90)
			(layer "B.SilkS")
			(hide yes)
			(effects
				(font
					(size 1.27 1.27)
				)
				(justify mirror)
			)
		)
		(property "Value" "*"
			(at 3.4036 -4.46405 270)
			(unlocked yes)
			(layer "B.Fab")
			(hide yes)
			(effects
				(font
					(size 0.889 0.889)
					(thickness 0.1524)
				)
				(justify mirror)
			)
		)
		(property "Device Type" "TEST-PAD-12P-1-GP-U_DISCRET-GBA"
			(at 3.4036 -5.98805 270)
			(unlocked yes)
			(layer "B.Fab")
			(hide yes)
			(effects
				(font
					(size 0.889 0.889)
					(thickness 0.1524)
				)
				(justify mirror)
			)
		)
		(duplicate_pad_numbers_are_jumpers no)
		(fp_line
			(start -2.3622 3.4798)
			(end 2.3876 3.4798)
			(stroke
				(width 0.1524)
				(type default)
			)
			(layer "B.SilkS")
		)
		(fp_line
			(start 2.3876 3.4798)
			(end 2.3876 -4.826)
			(stroke
				(width 0.1524)
				(type default)
			)
			(layer "B.SilkS")
		)
		(fp_line
			(start -2.3622 -4.826)
			(end -2.3622 3.4798)
			(stroke
				(width 0.1524)
				(type default)
			)
			(layer "B.SilkS")
		)
		(fp_line
			(start 2.3876 -4.826)
			(end -2.3622 -4.826)
			(stroke
				(width 0.1524)
				(type default)
			)
			(layer "B.SilkS")
		)
		(fp_rect
			(start 2.6416 3.7338)
			(end -2.6162 -5.08)
			(stroke
				(width 0)
				(type default)
			)
			(fill no)
			(layer "B.CrtYd")
		)
		(fp_rect
			(start 2.6416 3.7338)
			(end -2.6162 -5.08)
			(stroke
				(width 0)
				(type default)
			)
			(fill no)
			(layer "B.Fab")
		)
		(pad "1" smd circle
			(at -0.496824 -1.301496 90)
			(size 0.6604 0.6604)
			(layers "B.Cu" "B.Mask" "B.Paste")
			(net "L3_85OHM_10INCH_DP")
		)
		(pad "2" smd circle
			(at 0.503936 -1.301496 90)
			(size 0.6604 0.6604)
			(layers "B.Cu" "B.Mask" "B.Paste")
			(net "L3_85OHM_10INCH_DN")
		)
		(pad "3" smd custom
			(at 0.00889 0.370078 90)
			(size 0.74295 0.74295)
			(layers "B.Cu" "B.Mask" "B.Paste")
			(net "GND")
			(options
				(clearance outline)
				(anchor circle)
			)
			(primitives
				(gr_poly
					(pts
						(xy -2.1209 -1.4859) (xy 2.1209 -1.4859) (xy 2.1209 1.4859) (xy 1.08585 1.4859) (xy 1.08585 0.4699)
						(xy -1.08585 0.4699) (xy -1.08585 1.4859) (xy -2.1209 1.4859)
					)
					(width 0)
					(fill yes)
				)
			)
		)
		(pad "4" thru_hole circle
			(at -1.266444 -3.851656 90)
			(size 1.4478 1.4478)
			(drill 1.0414)
			(layers "*.Cu" "*.Mask")
			(remove_unused_layers no)
			(net "GND")
			(clearance 0.1524)
			(thermal_gap 0.1524)
		)
		(pad "5" thru_hole circle
			(at 1.273556 -3.851656 90)
			(size 1.4478 1.4478)
			(drill 1.0414)
			(layers "*.Cu" "*.Mask")
			(remove_unused_layers no)
			(net "GND")
			(clearance 0.1524)
			(thermal_gap 0.1524)
		)
		(pad "6" thru_hole circle
			(at -1.266444 2.498344 90)
			(size 1.4478 1.4478)
			(drill 1.0414)
			(layers "*.Cu" "*.Mask")
			(remove_unused_layers no)
			(net "GND")
			(clearance 0.1524)
			(thermal_gap 0.1524)
		)
		(pad "7" thru_hole circle
			(at 1.273556 2.498344 90)
			(size 1.4478 1.4478)
			(drill 1.0414)
			(layers "*.Cu" "*.Mask")
			(remove_unused_layers no)
			(net "GND")
			(clearance 0.1524)
			(thermal_gap 0.1524)
		)
		(pad "8" thru_hole circle
			(at -1.27 -0.4572 90)
			(size 0.7112 0.7112)
			(drill 0.4064)
			(layers "*.Cu" "*.Mask")
			(remove_unused_layers no)
			(net "GND")
			(clearance 0.1016)
			(thermal_gap 0.1016)
		)
		(pad "9" thru_hole circle
			(at -1.27 0.762 90)
			(size 0.7112 0.7112)
			(drill 0.4064)
			(layers "*.Cu" "*.Mask")
			(remove_unused_layers no)
			(net "GND")
			(clearance 0.1016)
			(thermal_gap 0.1016)
		)
		(pad "10" thru_hole circle
			(at 0.0254 0.762 90)
			(size 0.7112 0.7112)
			(drill 0.4064)
			(layers "*.Cu" "*.Mask")
			(remove_unused_layers no)
			(net "GND")
			(clearance 0.1016)
			(thermal_gap 0.1016)
		)
		(pad "11" thru_hole circle
			(at 1.27 0.762 90)
			(size 0.7112 0.7112)
			(drill 0.4064)
			(layers "*.Cu" "*.Mask")
			(remove_unused_layers no)
			(net "GND")
			(clearance 0.1016)
			(thermal_gap 0.1016)
		)
		(pad "12" thru_hole circle
			(at 1.27 -0.4572 90)
			(size 0.7112 0.7112)
			(drill 0.4064)
			(layers "*.Cu" "*.Mask")
			(remove_unused_layers no)
			(net "GND")
			(clearance 0.1016)
			(thermal_gap 0.1016)
		)
	)
	(footprint ""
		(layer "B.Cu")
		(at 497.794534 -38.029896 -90)
		(property "Reference" "R9F27"
			(at 0 0 90)
			(layer "B.SilkS")
			(hide yes)
			(effects
				(font
					(size 1.27 1.27)
				)
				(justify mirror)
			)
		)
		(property "Value" ""
			(at 0 0 90)
			(layer "B.Fab")
			(effects
				(font
					(size 1.27 1.27)
				)
				(justify mirror)
			)
		)
		(duplicate_pad_numbers_are_jumpers no)
		(fp_poly
			(pts
				(xy 0.2794 -0.1016) (xy -0.2794 -0.1016) (xy -0.2794 0.9906) (xy 0.2794 0.9906)
			)
			(stroke
				(width 0)
				(type default)
			)
			(fill no)
			(layer "B.CrtYd")
		)
		(fp_line
			(start -0.2794 0.9906)
			(end -0.2794 -0.1016)
			(stroke
				(width 0.1)
				(type default)
			)
			(layer "B.Fab")
		)
		(fp_line
			(start 0.2794 0.9906)
			(end -0.2794 0.9906)
			(stroke
				(width 0.1)
				(type default)
			)
			(layer "B.Fab")
		)
		(fp_line
			(start -0.2794 -0.1016)
			(end 0.2794 -0.1016)
			(stroke
				(width 0.1)
				(type default)
			)
			(layer "B.Fab")
		)
		(fp_line
			(start 0.2794 -0.1016)
			(end 0.2794 0.9906)
			(stroke
				(width 0.1)
				(type default)
			)
			(layer "B.Fab")
		)
		(pad "1" smd rect
			(at 0 0 90)
			(size 0.508 0.508)
			(layers "B.Cu" "B.Mask" "B.Paste")
			(net "UART_MUX_OUT_R")
		)
		(pad "2" smd rect
			(at 0 0.889 90)
			(size 0.508 0.508)
			(layers "B.Cu" "B.Mask" "B.Paste")
			(net "SPA_MID_DBG_TX")
		)
		(zone
			(layer "B.Cu")
			(hatch none 0.5)
			(connect_pads
				(clearance 0)
			)
			(min_thickness 0.25)
			(keepout
				(tracks not_allowed)
				(vias allowed)
				(pads allowed)
				(copperpour not_allowed)
				(footprints allowed)
			)
			(placement
				(enabled no)
				(sheetname "")
			)
			(fill
				(thermal_gap 0.5)
				(thermal_bridge_width 0.5)
				(island_removal_mode 0)
			)
			(polygon
				(pts
					(xy 497.159534 -37.775896) (xy 497.159534 -38.283896) (xy 497.540534 -38.283896) (xy 497.540534 -37.775896)
				)
			)
		)
		(zone
			(layer "B.Cu")
			(hatch none 0.5)
			(connect_pads
				(clearance 0)
			)
			(min_thickness 0.25)
			(keepout
				(tracks allowed)
				(vias not_allowed)
				(pads allowed)
				(copperpour not_allowed)
				(footprints allowed)
			)
			(placement
				(enabled no)
				(sheetname "")
			)
			(fill
				(thermal_gap 0.5)
				(thermal_bridge_width 0.5)
				(island_removal_mode 0)
			)
			(polygon
				(pts
					(xy 497.540534 -37.775896) (xy 497.540534 -38.283896) (xy 497.159534 -38.283896) (xy 497.159534 -37.775896)
				)
			)
		)
	)
	(footprint ""
		(layer "B.Cu")
		(at 431.609246 -17.585182 90)
		(property "Reference" "C1U19"
			(at 0 0 90)
			(layer "B.SilkS")
			(hide yes)
			(effects
				(font
					(size 1.27 1.27)
				)
				(justify mirror)
			)
		)
		(property "Value" ""
			(at 0 0 90)
			(layer "B.Fab")
			(effects
				(font
					(size 1.27 1.27)
				)
				(justify mirror)
			)
		)
		(duplicate_pad_numbers_are_jumpers no)
		(fp_poly
			(pts
				(xy -0.3048 -0.1016) (xy -0.3048 0.9906) (xy 0.3048 0.9906) (xy 0.3048 -0.1016)
			)
			(stroke
				(width 0)
				(type default)
			)
			(fill no)
			(layer "B.CrtYd")
		)
		(fp_line
			(start 0.3048 -0.1016)
			(end 0.3048 0.9906)
			(stroke
				(width 0.1)
				(type default)
			)
			(layer "B.Fab")
		)
		(fp_line
			(start -0.3048 -0.1016)
			(end 0.3048 -0.1016)
			(stroke
				(width 0.1)
				(type default)
			)
			(layer "B.Fab")
		)
		(fp_line
			(start 0.3048 0.9906)
			(end -0.3048 0.9906)
			(stroke
				(width 0.1)
				(type default)
			)
			(layer "B.Fab")
		)
		(fp_line
			(start -0.3048 0.9906)
			(end -0.3048 -0.1016)
			(stroke
				(width 0.1)
				(type default)
			)
			(layer "B.Fab")
		)
		(pad "1" smd rect
			(at 0 0 270)
			(size 0.508 0.508)
			(layers "B.Cu" "B.Mask" "B.Paste")
			(net "P3V3")
		)
		(pad "2" smd rect
			(at 0 0.889 270)
			(size 0.508 0.508)
			(layers "B.Cu" "B.Mask" "B.Paste")
			(net "GND")
		)
		(zone
			(layer "B.Cu")
			(hatch none 0.5)
			(connect_pads
				(clearance 0)
			)
			(min_thickness 0.25)
			(keepout
				(tracks allowed)
				(vias not_allowed)
				(pads allowed)
				(copperpour not_allowed)
				(footprints allowed)
			)
			(placement
				(enabled no)
				(sheetname "")
			)
			(fill
				(thermal_gap 0.5)
				(thermal_bridge_width 0.5)
				(island_removal_mode 0)
			)
			(polygon
				(pts
					(xy 431.863246 -17.839182) (xy 431.863246 -17.331182) (xy 432.244246 -17.331182) (xy 432.244246 -17.839182)
				)
			)
		)
		(zone
			(layer "B.Cu")
			(hatch none 0.5)
			(connect_pads
				(clearance 0)
			)
			(min_thickness 0.25)
			(keepout
				(tracks not_allowed)
				(vias allowed)
				(pads allowed)
				(copperpour not_allowed)
				(footprints allowed)
			)
			(placement
				(enabled no)
				(sheetname "")
			)
			(fill
				(thermal_gap 0.5)
				(thermal_bridge_width 0.5)
				(island_removal_mode 0)
			)
			(polygon
				(pts
					(xy 432.244246 -17.839182) (xy 432.244246 -17.331182) (xy 431.863246 -17.331182) (xy 431.863246 -17.839182)
				)
			)
		)
	)
	(footprint ""
		(layer "B.Cu")
		(at 348.615 -142.914624 -90)
		(property "Reference" "C3L16"
			(at 0 0 90)
			(layer "B.SilkS")
			(hide yes)
			(effects
				(font
					(size 1.27 1.27)
				)
				(justify mirror)
			)
		)
		(property "Value" ""
			(at 0 0 90)
			(layer "B.Fab")
			(effects
				(font
					(size 1.27 1.27)
				)
				(justify mirror)
			)
		)
		(duplicate_pad_numbers_are_jumpers no)
		(fp_poly
			(pts
				(xy 0.7239 -0.2159) (xy -0.7239 -0.2159) (xy -0.7239 1.9939) (xy 0.7239 1.9939)
			)
			(stroke
				(width 0)
				(type default)
			)
			(fill no)
			(layer "B.CrtYd")
		)
		(fp_line
			(start -0.7239 1.9939)
			(end -0.7239 -0.2159)
			(stroke
				(width 0.1)
				(type default)
			)
			(layer "B.Fab")
		)
		(fp_line
			(start 0.7239 1.9939)
			(end -0.7239 1.9939)
			(stroke
				(width 0.1)
				(type default)
			)
			(layer "B.Fab")
		)
		(fp_line
			(start -0.7239 -0.2159)
			(end 0.7239 -0.2159)
			(stroke
				(width 0.1)
				(type default)
			)
			(layer "B.Fab")
		)
		(fp_line
			(start 0.7239 -0.2159)
			(end 0.7239 1.9939)
			(stroke
				(width 0.1)
				(type default)
			)
			(layer "B.Fab")
		)
		(pad "1" smd rect
			(at 0 0 90)
			(size 1.27 1.016)
			(layers "B.Cu" "B.Mask" "B.Paste")
			(net "VR_FET_SW_P12V_STBY_PVDDQ_DEF")
		)
		(pad "2" smd rect
			(at 0 1.778 90)
			(size 1.27 1.016)
			(layers "B.Cu" "B.Mask" "B.Paste")
			(net "GND")
		)
		(zone
			(layer "B.Cu")
			(hatch none 0.5)
			(connect_pads
				(clearance 0)
			)
			(min_thickness 0.25)
			(keepout
				(tracks not_allowed)
				(vias allowed)
				(pads allowed)
				(copperpour not_allowed)
				(footprints allowed)
			)
			(placement
				(enabled no)
				(sheetname "")
			)
			(fill
				(thermal_gap 0.5)
				(thermal_bridge_width 0.5)
				(island_removal_mode 0)
			)
			(polygon
				(pts
					(xy 348.107 -142.279624) (xy 348.107 -143.549624) (xy 347.345 -143.549624) (xy 347.345 -142.279624)
				)
			)
		)
	)
)
